(kicad_pcb
	(version 20260206)
	(generator "pcbnew")
	(generator_version "10.0")
	(general
		(thickness 1.6)
		(legacy_teardrops no)
	)
	(paper "A4")
	(title_block
		(title "baseboard — 13948-1b.1110WZS1818.brd")
		(comment 1 "Honey Badger (Wiwynn) / footprints 2088-2096 of 2523")
	)
	(layers
		(0 "F.Cu" signal "TOP")
		(4 "In1.Cu" signal "L2GND")
		(6 "In2.Cu" signal "L3")
		(8 "In3.Cu" signal "L4VCC")
		(10 "In4.Cu" signal "L5VCC")
		(12 "In5.Cu" signal "L6")
		(14 "In6.Cu" signal "L7GND")
		(2 "B.Cu" signal "BOTTOM")
		(9 "F.Adhes" user "F.Adhesive")
		(11 "B.Adhes" user "B.Adhesive")
		(13 "F.Paste" user "Package Geometry/Pastemask Top")
		(15 "B.Paste" user "Package Geometry/Pastemask Bottom")
		(5 "F.SilkS" user "Ref Des/Silkscreen Top")
		(7 "B.SilkS" user "Ref Des/Silkscreen Bottom")
		(1 "F.Mask" user "Board Geometry/Soldermask Top")
		(3 "B.Mask" user "Board Geometry/Soldermask Bottom")
		(17 "Dwgs.User" user "User.Drawings")
		(19 "Cmts.User" user "User.Comments")
		(21 "Eco1.User" user "User.Eco1")
		(23 "Eco2.User" user "User.Eco2")
		(25 "Edge.Cuts" user "Board Geometry/Outline")
		(27 "Margin" user)
		(31 "F.CrtYd" user "Package Geometry/Place Bound Top")
		(29 "B.CrtYd" user "Package Geometry/Place Bound Bottom")
		(35 "F.Fab" user "Ref Des/Assembly Top")
		(33 "B.Fab" user "Ref Des/Assembly Bottom")
	)
	(footprint ""
		(layer "B.Cu")
		(at 110.75797 -86.868)
		(property "Reference" "STP157"
			(at 0 0 0)
			(layer "B.SilkS")
			(hide yes)
			(effects
				(font
					(size 1.27 1.27)
				)
				(justify mirror)
			)
		)
		(property "Value" "TPAD28"
			(at -0.0127 -1.8034 0)
			(unlocked yes)
			(layer "B.Fab")
			(hide yes)
			(effects
				(font
					(size 1.016 1.016)
					(thickness 0.1524)
				)
				(justify mirror)
			)
		)
		(property "Device Type" "TPAD28"
			(at -0.0127 -3.3274 0)
			(unlocked yes)
			(layer "B.Fab")
			(hide yes)
			(effects
				(font
					(size 1.016 1.016)
					(thickness 0.1524)
				)
				(justify mirror)
			)
		)
		(duplicate_pad_numbers_are_jumpers no)
		(fp_poly
			(pts
				(arc
					(start 0.3556 0)
					(mid -0.3556 0)
					(end 0.3556 0)
				)
			)
			(stroke
				(width 0)
				(type default)
			)
			(fill no)
			(layer "B.CrtYd")
		)
		(fp_poly
			(pts
				(arc
					(start 0.6096 0)
					(mid -0.6096 0)
					(end 0.6096 0)
				)
			)
			(stroke
				(width 0)
				(type default)
			)
			(fill no)
			(layer "B.Fab")
		)
		(pad "1" smd circle
			(at 0 0 180)
			(size 0.7112 0.7112)
			(layers "B.Cu" "B.Mask" "B.Paste")
			(net "EXP_LED_14")
		)
	)
	(footprint ""
		(layer "B.Cu")
		(at 16.76908 -231.822752)
		(property "Reference" "R517"
			(at 0 0 0)
			(layer "B.SilkS")
			(hide yes)
			(effects
				(font
					(size 1.27 1.27)
				)
				(justify mirror)
			)
		)
		(property "Value" "0R2J-2-GP"
			(at -0.064008 -3.993896 0)
			(unlocked yes)
			(layer "B.Fab")
			(hide yes)
			(effects
				(font
					(size 1.016 1.016)
					(thickness 0.1524)
				)
				(justify mirror)
			)
		)
		(property "Device Type" "R402H16"
			(at -0.064008 -5.517896 0)
			(unlocked yes)
			(layer "B.Fab")
			(hide yes)
			(effects
				(font
					(size 1.016 1.016)
					(thickness 0.1524)
				)
				(justify mirror)
			)
		)
		(duplicate_pad_numbers_are_jumpers no)
		(fp_line
			(start -0.508 -0.9398)
			(end 0.508 -0.9398)
			(stroke
				(width 0.1524)
				(type default)
			)
			(layer "B.SilkS")
		)
		(fp_line
			(start 0.508 -0.9398)
			(end 0.508 0.9398)
			(stroke
				(width 0.1524)
				(type default)
			)
			(layer "B.SilkS")
		)
		(fp_rect
			(start 0.508 0.9398)
			(end -0.508 -0.9398)
			(stroke
				(width 0)
				(type default)
			)
			(fill no)
			(layer "B.CrtYd")
		)
		(fp_rect
			(start 0.508 0.9398)
			(end -0.508 -0.9398)
			(stroke
				(width 0)
				(type default)
			)
			(fill no)
			(layer "B.Fab")
		)
		(pad "1" smd custom
			(at 0 -0.4445 180)
			(size 0.1397 0.1397)
			(layers "B.Cu" "B.Mask" "B.Paste")
			(net "SAS_HDD_PWR15_PCIE")
			(options
				(clearance outline)
				(anchor circle)
			)
			(primitives
				(gr_poly
					(pts
						(arc
							(start -0.1778 0.2794)
							(mid -0.249642 0.249642)
							(end -0.2794 0.1778)
						)
						(arc
							(start -0.2794 -0.1778)
							(mid -0.249642 -0.249642)
							(end -0.1778 -0.2794)
						)
						(arc
							(start 0.1778 -0.2794)
							(mid 0.249642 -0.249642)
							(end 0.2794 -0.1778)
						)
						(arc
							(start 0.2794 0.1778)
							(mid 0.249642 0.249642)
							(end 0.1778 0.2794)
						)
					)
					(width 0)
					(fill yes)
				)
			)
		)
		(pad "2" smd custom
			(at 0 0.4445 180)
			(size 0.1397 0.1397)
			(layers "B.Cu" "B.Mask" "B.Paste")
			(net "SAS_HDD_PWR15")
			(options
				(clearance outline)
				(anchor circle)
			)
			(primitives
				(gr_poly
					(pts
						(arc
							(start -0.1778 0.2794)
							(mid -0.249642 0.249642)
							(end -0.2794 0.1778)
						)
						(arc
							(start -0.2794 -0.1778)
							(mid -0.249642 -0.249642)
							(end -0.1778 -0.2794)
						)
						(arc
							(start 0.1778 -0.2794)
							(mid 0.249642 -0.249642)
							(end 0.2794 -0.1778)
						)
						(arc
							(start 0.2794 0.1778)
							(mid 0.249642 0.249642)
							(end 0.1778 0.2794)
						)
					)
					(width 0)
					(fill yes)
				)
			)
		)
	)
	(footprint ""
		(layer "B.Cu")
		(at 103.89616 -36.83 180)
		(property "Reference" "SC943"
			(at 0 0 0)
			(layer "B.SilkS")
			(hide yes)
			(effects
				(font
					(size 1.27 1.27)
				)
				(justify mirror)
			)
		)
		(property "Value" "SCD1U6D3V1KX-GP"
			(at 2.8321 -1.7399 180)
			(unlocked yes)
			(layer "B.Fab")
			(hide yes)
			(effects
				(font
					(size 1.016 1.016)
					(thickness 0.1524)
				)
				(justify mirror)
			)
		)
		(property "Device Type" "C0201H13"
			(at 2.8321 -3.2639 180)
			(unlocked yes)
			(layer "B.Fab")
			(hide yes)
			(effects
				(font
					(size 1.016 1.016)
					(thickness 0.1524)
				)
				(justify mirror)
			)
		)
		(duplicate_pad_numbers_are_jumpers no)
		(fp_rect
			(start 0.2794 0.6477)
			(end -0.2794 -0.6477)
			(stroke
				(width 0)
				(type default)
			)
			(fill no)
			(layer "B.CrtYd")
		)
		(fp_rect
			(start 0.2794 0.6477)
			(end -0.2794 -0.6477)
			(stroke
				(width 0)
				(type default)
			)
			(fill no)
			(layer "B.Fab")
		)
		(pad "1" smd custom
			(at 0 -0.2794)
			(size 0.0762 0.0762)
			(layers "B.Cu" "B.Mask" "B.Paste")
			(net "P1V5_C")
			(options
				(clearance outline)
				(anchor circle)
			)
			(primitives
				(gr_poly
					(pts
						(arc
							(start 0.1524 0.127)
							(mid 0.137521 0.162921)
							(end 0.1016 0.1778)
						)
						(arc
							(start -0.1016 0.1778)
							(mid -0.137521 0.162921)
							(end -0.1524 0.127)
						)
						(arc
							(start -0.1524 -0.127)
							(mid -0.137521 -0.162921)
							(end -0.1016 -0.1778)
						)
						(arc
							(start 0.1016 -0.1778)
							(mid 0.137521 -0.162921)
							(end 0.1524 -0.127)
						)
					)
					(width 0)
					(fill yes)
				)
			)
		)
		(pad "2" smd custom
			(at 0 0.2794)
			(size 0.0762 0.0762)
			(layers "B.Cu" "B.Mask" "B.Paste")
			(net "GND")
			(options
				(clearance outline)
				(anchor circle)
			)
			(primitives
				(gr_poly
					(pts
						(arc
							(start 0.1524 0.127)
							(mid 0.137521 0.162921)
							(end 0.1016 0.1778)
						)
						(arc
							(start -0.1016 0.1778)
							(mid -0.137521 0.162921)
							(end -0.1524 0.127)
						)
						(arc
							(start -0.1524 -0.127)
							(mid -0.137521 -0.162921)
							(end -0.1016 -0.1778)
						)
						(arc
							(start 0.1016 -0.1778)
							(mid 0.137521 -0.162921)
							(end 0.1524 -0.127)
						)
					)
					(width 0)
					(fill yes)
				)
			)
		)
	)
	(footprint ""
		(layer "B.Cu")
		(at 111.44377 -83.1088 -90)
		(property "Reference" "SC1222"
			(at 0 0 90)
			(layer "B.SilkS")
			(hide yes)
			(effects
				(font
					(size 1.27 1.27)
				)
				(justify mirror)
			)
		)
		(property "Value" "SCD1U6D3V1KX-GP"
			(at 2.8321 -1.7399 270)
			(unlocked yes)
			(layer "B.Fab")
			(hide yes)
			(effects
				(font
					(size 1.016 1.016)
					(thickness 0.1524)
				)
				(justify mirror)
			)
		)
		(property "Device Type" "C0201H13"
			(at 2.8321 -3.2639 270)
			(unlocked yes)
			(layer "B.Fab")
			(hide yes)
			(effects
				(font
					(size 1.016 1.016)
					(thickness 0.1524)
				)
				(justify mirror)
			)
		)
		(duplicate_pad_numbers_are_jumpers no)
		(fp_rect
			(start 0.2794 0.6477)
			(end -0.2794 -0.6477)
			(stroke
				(width 0)
				(type default)
			)
			(fill no)
			(layer "B.CrtYd")
		)
		(fp_rect
			(start 0.2794 0.6477)
			(end -0.2794 -0.6477)
			(stroke
				(width 0)
				(type default)
			)
			(fill no)
			(layer "B.Fab")
		)
		(pad "1" smd custom
			(at 0 -0.2794 90)
			(size 0.0762 0.0762)
			(layers "B.Cu" "B.Mask" "B.Paste")
			(net "P1V8_E")
			(options
				(clearance outline)
				(anchor circle)
			)
			(primitives
				(gr_poly
					(pts
						(arc
							(start 0.1524 0.127)
							(mid 0.137521 0.162921)
							(end 0.1016 0.1778)
						)
						(arc
							(start -0.1016 0.1778)
							(mid -0.137521 0.162921)
							(end -0.1524 0.127)
						)
						(arc
							(start -0.1524 -0.127)
							(mid -0.137521 -0.162921)
							(end -0.1016 -0.1778)
						)
						(arc
							(start 0.1016 -0.1778)
							(mid 0.137521 -0.162921)
							(end 0.1524 -0.127)
						)
					)
					(width 0)
					(fill yes)
				)
			)
		)
		(pad "2" smd custom
			(at 0 0.2794 90)
			(size 0.0762 0.0762)
			(layers "B.Cu" "B.Mask" "B.Paste")
			(net "GND")
			(options
				(clearance outline)
				(anchor circle)
			)
			(primitives
				(gr_poly
					(pts
						(arc
							(start 0.1524 0.127)
							(mid 0.137521 0.162921)
							(end 0.1016 0.1778)
						)
						(arc
							(start -0.1016 0.1778)
							(mid -0.137521 0.162921)
							(end -0.1524 0.127)
						)
						(arc
							(start -0.1524 -0.127)
							(mid -0.137521 -0.162921)
							(end -0.1016 -0.1778)
						)
						(arc
							(start 0.1016 -0.1778)
							(mid 0.137521 -0.162921)
							(end 0.1524 -0.127)
						)
					)
					(width 0)
					(fill yes)
				)
			)
		)
	)
	(footprint ""
		(layer "B.Cu")
		(at 127.72517 -85.7758 90)
		(property "Reference" "SC1159"
			(at 0 0 90)
			(layer "B.SilkS")
			(hide yes)
			(effects
				(font
					(size 1.27 1.27)
				)
				(justify mirror)
			)
		)
		(property "Value" "SC22U6D3V5MX-2GP"
			(at 0.0762 -6.1214 90)
			(unlocked yes)
			(layer "B.Fab")
			(hide yes)
			(effects
				(font
					(size 1.016 1.016)
					(thickness 0.1524)
				)
				(justify mirror)
			)
		)
		(property "Device Type" "C805H58"
			(at 0.0762 -8.1534 90)
			(unlocked yes)
			(layer "B.Fab")
			(hide yes)
			(effects
				(font
					(size 1.016 1.016)
					(thickness 0.1524)
				)
				(justify mirror)
			)
		)
		(duplicate_pad_numbers_are_jumpers no)
		(fp_line
			(start -0.635 0)
			(end 0.635 0)
			(stroke
				(width 0.508)
				(type default)
			)
			(layer "B.SilkS")
		)
		(fp_rect
			(start 0.9652 1.778)
			(end -0.9652 -1.778)
			(stroke
				(width 0)
				(type default)
			)
			(fill no)
			(layer "B.CrtYd")
		)
		(fp_poly
			(pts
				(xy 0.9652 -1.778) (xy -0.9652 -1.778) (xy -0.9652 1.778) (xy 0.9652 1.778)
			)
			(stroke
				(width 0)
				(type default)
			)
			(fill no)
			(layer "B.Fab")
		)
		(pad "1" smd rect
			(at 0 -0.9652 270)
			(size 1.397 1.143)
			(layers "B.Cu" "B.Mask" "B.Paste")
			(net "GB_VDDA")
		)
		(pad "2" smd rect
			(at 0 0.9652 270)
			(size 1.397 1.143)
			(layers "B.Cu" "B.Mask" "B.Paste")
			(net "GND")
		)
	)
	(footprint ""
		(layer "B.Cu")
		(at 133.585966 -32.766 -90)
		(property "Reference" "SR657"
			(at 0 0 90)
			(layer "B.SilkS")
			(hide yes)
			(effects
				(font
					(size 1.27 1.27)
				)
				(justify mirror)
			)
		)
		(property "Value" "10KR2F-2-GP"
			(at -0.064008 -3.993896 270)
			(unlocked yes)
			(layer "B.Fab")
			(hide yes)
			(effects
				(font
					(size 1.016 1.016)
					(thickness 0.1524)
				)
				(justify mirror)
			)
		)
		(property "Device Type" "R402H16"
			(at -0.064008 -5.517896 270)
			(unlocked yes)
			(layer "B.Fab")
			(hide yes)
			(effects
				(font
					(size 1.016 1.016)
					(thickness 0.1524)
				)
				(justify mirror)
			)
		)
		(duplicate_pad_numbers_are_jumpers no)
		(fp_line
			(start -0.508 -0.9398)
			(end 0.508 -0.9398)
			(stroke
				(width 0.1524)
				(type default)
			)
			(layer "B.SilkS")
		)
		(fp_line
			(start 0.508 -0.9398)
			(end 0.508 0.9398)
			(stroke
				(width 0.1524)
				(type default)
			)
			(layer "B.SilkS")
		)
		(fp_rect
			(start 0.508 0.9398)
			(end -0.508 -0.9398)
			(stroke
				(width 0)
				(type default)
			)
			(fill no)
			(layer "B.CrtYd")
		)
		(fp_rect
			(start 0.508 0.9398)
			(end -0.508 -0.9398)
			(stroke
				(width 0)
				(type default)
			)
			(fill no)
			(layer "B.Fab")
		)
		(pad "1" smd custom
			(at 0 -0.4445 90)
			(size 0.1397 0.1397)
			(layers "B.Cu" "B.Mask" "B.Paste")
			(net "P3V3_STBY_R")
			(options
				(clearance outline)
				(anchor circle)
			)
			(primitives
				(gr_poly
					(pts
						(arc
							(start -0.1778 0.2794)
							(mid -0.249642 0.249642)
							(end -0.2794 0.1778)
						)
						(arc
							(start -0.2794 -0.1778)
							(mid -0.249642 -0.249642)
							(end -0.1778 -0.2794)
						)
						(arc
							(start 0.1778 -0.2794)
							(mid 0.249642 -0.249642)
							(end 0.2794 -0.1778)
						)
						(arc
							(start 0.2794 0.1778)
							(mid 0.249642 0.249642)
							(end 0.1778 0.2794)
						)
					)
					(width 0)
					(fill yes)
				)
			)
		)
		(pad "2" smd custom
			(at 0 0.4445 90)
			(size 0.1397 0.1397)
			(layers "B.Cu" "B.Mask" "B.Paste")
			(net "P3V3_STBY_B")
			(options
				(clearance outline)
				(anchor circle)
			)
			(primitives
				(gr_poly
					(pts
						(arc
							(start -0.1778 0.2794)
							(mid -0.249642 0.249642)
							(end -0.2794 0.1778)
						)
						(arc
							(start -0.2794 -0.1778)
							(mid -0.249642 -0.249642)
							(end -0.1778 -0.2794)
						)
						(arc
							(start 0.1778 -0.2794)
							(mid 0.249642 -0.249642)
							(end 0.2794 -0.1778)
						)
						(arc
							(start 0.2794 0.1778)
							(mid 0.249642 0.249642)
							(end 0.1778 0.2794)
						)
					)
					(width 0)
					(fill yes)
				)
			)
		)
	)
	(footprint ""
		(layer "B.Cu")
		(at 108.020612 -216.154 -90)
		(property "Reference" "SR901"
			(at 0 0 90)
			(layer "B.SilkS")
			(hide yes)
			(effects
				(font
					(size 1.27 1.27)
				)
				(justify mirror)
			)
		)
		(property "Value" "4K7R2F-GP"
			(at -0.064008 -3.993896 270)
			(unlocked yes)
			(layer "B.Fab")
			(hide yes)
			(effects
				(font
					(size 1.016 1.016)
					(thickness 0.1524)
				)
				(justify mirror)
			)
		)
		(property "Device Type" "R402H16"
			(at -0.064008 -5.517896 270)
			(unlocked yes)
			(layer "B.Fab")
			(hide yes)
			(effects
				(font
					(size 1.016 1.016)
					(thickness 0.1524)
				)
				(justify mirror)
			)
		)
		(duplicate_pad_numbers_are_jumpers no)
		(fp_line
			(start -0.508 -0.9398)
			(end 0.508 -0.9398)
			(stroke
				(width 0.1524)
				(type default)
			)
			(layer "B.SilkS")
		)
		(fp_line
			(start 0.508 -0.9398)
			(end 0.508 0.9398)
			(stroke
				(width 0.1524)
				(type default)
			)
			(layer "B.SilkS")
		)
		(fp_rect
			(start 0.508 0.9398)
			(end -0.508 -0.9398)
			(stroke
				(width 0)
				(type default)
			)
			(fill no)
			(layer "B.CrtYd")
		)
		(fp_rect
			(start 0.508 0.9398)
			(end -0.508 -0.9398)
			(stroke
				(width 0)
				(type default)
			)
			(fill no)
			(layer "B.Fab")
		)
		(pad "1" smd custom
			(at 0 -0.4445 90)
			(size 0.1397 0.1397)
			(layers "B.Cu" "B.Mask" "B.Paste")
			(net "REDV_I2C_A1")
			(options
				(clearance outline)
				(anchor circle)
			)
			(primitives
				(gr_poly
					(pts
						(arc
							(start -0.1778 0.2794)
							(mid -0.249642 0.249642)
							(end -0.2794 0.1778)
						)
						(arc
							(start -0.2794 -0.1778)
							(mid -0.249642 -0.249642)
							(end -0.1778 -0.2794)
						)
						(arc
							(start 0.1778 -0.2794)
							(mid 0.249642 -0.249642)
							(end 0.2794 -0.1778)
						)
						(arc
							(start 0.2794 0.1778)
							(mid 0.249642 0.249642)
							(end 0.1778 0.2794)
						)
					)
					(width 0)
					(fill yes)
				)
			)
		)
		(pad "2" smd custom
			(at 0 0.4445 90)
			(size 0.1397 0.1397)
			(layers "B.Cu" "B.Mask" "B.Paste")
			(net "GND")
			(options
				(clearance outline)
				(anchor circle)
			)
			(primitives
				(gr_poly
					(pts
						(arc
							(start -0.1778 0.2794)
							(mid -0.249642 0.249642)
							(end -0.2794 0.1778)
						)
						(arc
							(start -0.2794 -0.1778)
							(mid -0.249642 -0.249642)
							(end -0.1778 -0.2794)
						)
						(arc
							(start 0.1778 -0.2794)
							(mid 0.249642 -0.249642)
							(end 0.2794 -0.1778)
						)
						(arc
							(start 0.2794 0.1778)
							(mid 0.249642 0.249642)
							(end 0.1778 0.2794)
						)
					)
					(width 0)
					(fill yes)
				)
			)
		)
	)
	(footprint ""
		(layer "B.Cu")
		(at 86.087966 -48.006 90)
		(property "Reference" "SR627"
			(at 0 0 90)
			(layer "B.SilkS")
			(hide yes)
			(effects
				(font
					(size 1.27 1.27)
				)
				(justify mirror)
			)
		)
		(property "Value" "2K2R2F-GP"
			(at -0.064008 -3.993896 90)
			(unlocked yes)
			(layer "B.Fab")
			(hide yes)
			(effects
				(font
					(size 1.016 1.016)
					(thickness 0.1524)
				)
				(justify mirror)
			)
		)
		(property "Device Type" "R402H16"
			(at -0.064008 -5.517896 90)
			(unlocked yes)
			(layer "B.Fab")
			(hide yes)
			(effects
				(font
					(size 1.016 1.016)
					(thickness 0.1524)
				)
				(justify mirror)
			)
		)
		(duplicate_pad_numbers_are_jumpers no)
		(fp_line
			(start 0.508 -0.9398)
			(end 0.508 0.9398)
			(stroke
				(width 0.1524)
				(type default)
			)
			(layer "B.SilkS")
		)
		(fp_line
			(start -0.508 -0.9398)
			(end 0.508 -0.9398)
			(stroke
				(width 0.1524)
				(type default)
			)
			(layer "B.SilkS")
		)
		(fp_rect
			(start 0.508 0.9398)
			(end -0.508 -0.9398)
			(stroke
				(width 0)
				(type default)
			)
			(fill no)
			(layer "B.CrtYd")
		)
		(fp_rect
			(start 0.508 0.9398)
			(end -0.508 -0.9398)
			(stroke
				(width 0)
				(type default)
			)
			(fill no)
			(layer "B.Fab")
		)
		(pad "1" smd custom
			(at 0 -0.4445 270)
			(size 0.1397 0.1397)
			(layers "B.Cu" "B.Mask" "B.Paste")
			(net "P1V8_C")
			(options
				(clearance outline)
				(anchor circle)
			)
			(primitives
				(gr_poly
					(pts
						(arc
							(start -0.1778 0.2794)
							(mid -0.249642 0.249642)
							(end -0.2794 0.1778)
						)
						(arc
							(start -0.2794 -0.1778)
							(mid -0.249642 -0.249642)
							(end -0.1778 -0.2794)
						)
						(arc
							(start 0.1778 -0.2794)
							(mid 0.249642 -0.249642)
							(end 0.2794 -0.1778)
						)
						(arc
							(start 0.2794 0.1778)
							(mid 0.249642 0.249642)
							(end 0.1778 0.2794)
						)
					)
					(width 0)
					(fill yes)
				)
			)
		)
		(pad "2" smd custom
			(at 0 0.4445 270)
			(size 0.1397 0.1397)
			(layers "B.Cu" "B.Mask" "B.Paste")
			(net "SIO_DIN_0")
			(options
				(clearance outline)
				(anchor circle)
			)
			(primitives
				(gr_poly
					(pts
						(arc
							(start -0.1778 0.2794)
							(mid -0.249642 0.249642)
							(end -0.2794 0.1778)
						)
						(arc
							(start -0.2794 -0.1778)
							(mid -0.249642 -0.249642)
							(end -0.1778 -0.2794)
						)
						(arc
							(start 0.1778 -0.2794)
							(mid 0.249642 -0.249642)
							(end 0.2794 -0.1778)
						)
						(arc
							(start 0.2794 0.1778)
							(mid 0.249642 0.249642)
							(end 0.1778 0.2794)
						)
					)
					(width 0)
					(fill yes)
				)
			)
		)
	)
	(footprint ""
		(layer "B.Cu")
		(at 108.085128 -57.946798)
		(property "Reference" "STP159"
			(at 0 0 0)
			(layer "B.SilkS")
			(hide yes)
			(effects
				(font
					(size 1.27 1.27)
				)
				(justify mirror)
			)
		)
		(property "Value" "TPAD28"
			(at -0.0127 -1.8034 0)
			(unlocked yes)
			(layer "B.Fab")
			(hide yes)
			(effects
				(font
					(size 1.016 1.016)
					(thickness 0.1524)
				)
				(justify mirror)
			)
		)
		(property "Device Type" "TPAD28"
			(at -0.0127 -3.3274 0)
			(unlocked yes)
			(layer "B.Fab")
			(hide yes)
			(effects
				(font
					(size 1.016 1.016)
					(thickness 0.1524)
				)
				(justify mirror)
			)
		)
		(duplicate_pad_numbers_are_jumpers no)
		(fp_poly
			(pts
				(arc
					(start 0.3556 0)
					(mid -0.3556 0)
					(end 0.3556 0)
				)
			)
			(stroke
				(width 0)
				(type default)
			)
			(fill no)
			(layer "B.CrtYd")
		)
		(fp_poly
			(pts
				(arc
					(start 0.6096 0)
					(mid -0.6096 0)
					(end 0.6096 0)
				)
			)
			(stroke
				(width 0)
				(type default)
			)
			(fill no)
			(layer "B.Fab")
		)
		(pad "1" smd circle
			(at 0 0 180)
			(size 0.7112 0.7112)
			(layers "B.Cu" "B.Mask" "B.Paste")
			(net "XM_RB")
		)
	)
)
